(kicad_pcb
	(version 20241229)
	(generator "pcbnew")
	(generator_version "9.0")
	(general
		(thickness 1.61)
		(legacy_teardrops no)
	)
	(paper "A3")
	(title_block
		(title "RDIMM DDR5 Tester")
		(date "2026-05-21")
		(rev "2.2.0")
		(company "Antmicro")
		(comment 9 "footprints 373-374 of 796")
	)
	(layers
		(0 "F.Cu" signal)
		(4 "In1.Cu" power)
		(6 "In2.Cu" mixed)
		(8 "In3.Cu" power)
		(10 "In4.Cu" mixed)
		(12 "In5.Cu" power)
		(14 "In6.Cu" mixed)
		(16 "In7.Cu" power)
		(18 "In8.Cu" power)
		(20 "In9.Cu" mixed)
		(22 "In10.Cu" power)
		(2 "B.Cu" signal)
		(9 "F.Adhes" user "F.Adhesive")
		(11 "B.Adhes" user "B.Adhesive")
		(13 "F.Paste" user)
		(15 "B.Paste" user)
		(5 "F.SilkS" user "F.Silkscreen")
		(7 "B.SilkS" user "B.Silkscreen")
		(1 "F.Mask" user)
		(3 "B.Mask" user)
		(17 "Dwgs.User" user "User.Drawings")
		(19 "Cmts.User" user "User.Comments")
		(21 "Eco1.User" user "User.Eco1")
		(23 "Eco2.User" user "User.Eco2")
		(25 "Edge.Cuts" user)
		(27 "Margin" user)
		(31 "F.CrtYd" user "F.Courtyard")
		(29 "B.CrtYd" user "B.Courtyard")
		(35 "F.Fab" user)
		(33 "B.Fab" user)
	)
	(footprint "antmicro-footprints:MP_Pad6mm_Drill3mm"
		(layer "F.Cu")
		(at 107.5 193.4)
		(property "Reference" "MP2"
			(at 0 -3.2 0)
			(layer "F.SilkS")
			(hide yes)
			(effects
				(font
					(size 0.7 0.7)
					(thickness 0.15)
				)
				(justify left bottom)
			)
		)
		(property "Value" "MP_Pad6mm_Drill3mm"
			(at 0 3.9 0)
			(layer "F.Fab")
			(effects
				(font
					(size 0.7 0.7)
					(thickness 0.15)
				)
				(justify left bottom)
			)
		)
		(attr board_only exclude_from_pos_files exclude_from_bom)
		(fp_circle
			(center 0 0)
			(end 3.25 0)
			(stroke
				(width 0.05)
				(type default)
			)
			(fill no)
			(layer "F.CrtYd")
		)
		(fp_text user "Author: Antmicro"
			(at -0.178 7.225 0)
			(layer "F.Fab")
			(effects
				(font
					(size 0.7 0.7)
					(thickness 0.15)
				)
				(justify left bottom)
			)
		)
		(fp_text user "${REFERENCE}"
			(at -0.178 6.025 0)
			(layer "F.Fab")
			(effects
				(font
					(size 0.7 0.7)
					(thickness 0.15)
				)
				(justify left bottom)
			)
		)
		(fp_text user "License: Apache-2.0"
			(at -0.178 8.425 0)
			(layer "F.Fab")
			(effects
				(font
					(size 0.7 0.7)
					(thickness 0.15)
				)
				(justify left bottom)
			)
		)
		(pad "1" thru_hole circle
			(at 0 0)
			(size 6 6)
			(drill 3)
			(layers "*.Cu" "*.Mask")
			(remove_unused_layers no)
			(net 1 "GND")
		)
	)
	(footprint "antmicro-footprints:Fiducial_1mm_Mask2mm"
		(layer "F.Cu")
		(at 259.8 182.15 180)
		(descr "Circular Fiducial, 1mm bare copper, 3mm soldermask opening")
		(tags "fiducial")
		(property "Reference" "FID1005"
			(at 0 -1.4 0)
			(layer "F.SilkS")
			(hide yes)
			(effects
				(font
					(size 0.7 0.7)
					(thickness 0.15)
				)
				(justify right bottom)
			)
		)
		(property "Value" "Fiducial_1mm_Mask2mm"
			(at 0 2.2 0)
			(layer "F.Fab")
			(effects
				(font
					(size 0.7 0.7)
					(thickness 0.15)
				)
				(justify right bottom)
			)
		)
		(sheetfile "data-center-rdimm-ddr5-tester.kicad_sch")
		(attr board_only exclude_from_pos_files exclude_from_bom)
		(fp_circle
			(center 0 0)
			(end 1.24 0)
			(stroke
				(width 0.05)
				(type solid)
			)
			(fill no)
			(layer "F.CrtYd")
		)
		(fp_circle
			(center 0 0)
			(end 0.999 0)
			(stroke
				(width 0.15)
				(type solid)
			)
			(fill no)
			(layer "F.Fab")
		)
		(fp_text user "Author: Antmicro"
			(at -1.25 5.803 180)
			(layer "F.Fab")
			(effects
				(font
					(size 0.7 0.7)
					(thickness 0.15)
				)
				(justify left bottom)
			)
		)
		(fp_text user "License: Apache-2.0"
			(at -1.25 7.003 180)
			(layer "F.Fab")
			(effects
				(font
					(size 0.7 0.7)
					(thickness 0.15)
				)
				(justify left bottom)
			)
		)
		(fp_text user "${REFERENCE}"
			(at -1.25 4.603 180)
			(layer "F.Fab")
			(effects
				(font
					(size 0.7 0.7)
					(thickness 0.15)
				)
				(justify left bottom)
			)
		)
		(pad "" smd circle
			(at 0 0 180)
			(size 1 1)
			(layers "F.Cu" "F.Mask")
			(solder_mask_margin 0.5)
			(clearance 0.5)
		)
	)
)
